# T6G (Grand Teton) — schematic netlist excerpt (pin names and nets, part order shuffled) for the footprints in the layout excerpt that follows; sources: Cadence DE-HDL packaged netlist, KiCad conversion of 04192023_DAF0TMB3IC0_F0TG_MB_C_brd_V02_OCP.brd

PC6625_1  Q_CAP  22UF 4V 20% X6S  pkg C0805  page 365 : A = P0V9_CPU1_RT_2D ; B = GND
C803  Q_CAP  10UF 6.3V 20% X6S  pkg C0402  page 301 : A = P0V9_CPU0_RT2_2A ; B = GND
R1512  Q_RES  1K 1% EMPTY  pkg 0201LF  page 353 : A = P1V8_CPU1_RT_1D ; B = JTAG_TDO_RT_CPU1_P3

(kicad_pcb
	(version 20260206)
	(generator "pcbnew")
	(generator_version "10.0")
	(general
		(thickness 1.6)
		(legacy_teardrops no)
	)
	(paper "A4")
	(title_block
		(title "04192023_DAF0TMB3IC0_F0TG_MB_C_brd_V02_OCP.brd")
		(comment 1 "Grand Teton / footprints 6847-6849 of 8354")
	)
	(layers
		(0 "F.Cu" signal "TOP")
		(4 "In1.Cu" signal "GND")
		(6 "In2.Cu" signal "IN1")
		(8 "In3.Cu" signal "GND1")
		(10 "In4.Cu" signal "IN2")
		(12 "In5.Cu" signal "GND2")
		(14 "In6.Cu" signal "IN3")
		(16 "In7.Cu" signal "GND3")
		(18 "In8.Cu" signal "VCC")
		(20 "In9.Cu" signal "VCC1")
		(22 "In10.Cu" signal "GND4")
		(24 "In11.Cu" signal "IN4")
		(26 "In12.Cu" signal "GND5")
		(28 "In13.Cu" signal "IN5")
		(30 "In14.Cu" signal "GND6")
		(32 "In15.Cu" signal "IN6")
		(34 "In16.Cu" signal "GND7")
		(2 "B.Cu" signal "BOTTOM")
		(9 "F.Adhes" user "F.Adhesive")
		(11 "B.Adhes" user "B.Adhesive")
		(13 "F.Paste" user "Package Geometry/Pastemask Top")
		(15 "B.Paste" user "Package Geometry/Pastemask Bottom")
		(5 "F.SilkS" user "Ref Des/Silkscreen Top")
		(7 "B.SilkS" user "Ref Des/Silkscreen Bottom")
		(1 "F.Mask" user "Board Geometry/Soldermask Top")
		(3 "B.Mask" user "Board Geometry/Soldermask Bottom")
		(17 "Dwgs.User" user "User.Drawings")
		(19 "Cmts.User" user "User.Comments")
		(21 "Eco1.User" user "User.Eco1")
		(23 "Eco2.User" user "User.Eco2")
		(25 "Edge.Cuts" user "Board Geometry/Outline")
		(27 "Margin" user)
		(31 "F.CrtYd" user "Package Geometry/Place Bound Top")
		(29 "B.CrtYd" user "Package Geometry/Place Bound Bottom")
		(35 "F.Fab" user "Ref Des/Assembly Top")
		(33 "B.Fab" user "Ref Des/Assembly Bottom")
	)
	(footprint ""
		(layer "B.Cu")
		(at 10.91057 -383.051558 -90)
		(property "Reference" "PC6625_1"
			(at 0 0 90)
			(layer "B.SilkS")
			(hide yes)
			(effects
				(font
					(size 1.27 1.27)
				)
				(justify mirror)
			)
		)
		(property "Value" ""
			(at 0 0 90)
			(layer "B.Fab")
			(effects
				(font
					(size 1.27 1.27)
				)
				(justify mirror)
			)
		)
		(duplicate_pad_numbers_are_jumpers no)
		(fp_line
			(start -1.524 0.762)
			(end 1.524 0.762)
			(stroke
				(width 0.1524)
				(type default)
			)
			(layer "B.SilkS")
		)
		(fp_line
			(start 1.524 0.762)
			(end 1.524 -0.762)
			(stroke
				(width 0.1524)
				(type default)
			)
			(layer "B.SilkS")
		)
		(fp_line
			(start -1.524 -0.762)
			(end -1.524 0.762)
			(stroke
				(width 0.1524)
				(type default)
			)
			(layer "B.SilkS")
		)
		(fp_line
			(start 1.524 -0.762)
			(end -1.524 -0.762)
			(stroke
				(width 0.1524)
				(type default)
			)
			(layer "B.SilkS")
		)
		(fp_line
			(start -1.1049 0.724916)
			(end -1.1049 -0.724916)
			(stroke
				(width 0.1)
				(type default)
			)
			(layer "B.Fab")
		)
		(fp_line
			(start 1.1049 0.724916)
			(end -1.1049 0.724916)
			(stroke
				(width 0.1)
				(type default)
			)
			(layer "B.Fab")
		)
		(fp_line
			(start -1.1049 -0.724916)
			(end 1.1049 -0.724916)
			(stroke
				(width 0.1)
				(type default)
			)
			(layer "B.Fab")
		)
		(fp_line
			(start 1.1049 -0.724916)
			(end 1.1049 0.724916)
			(stroke
				(width 0.1)
				(type default)
			)
			(layer "B.Fab")
		)
		(pad "1" smd rect
			(at 0.889 0 270)
			(size 1.016 1.27)
			(layers "B.Cu" "B.Mask" "B.Paste")
			(net "P0V9_CPU1_RT_2D")
		)
		(pad "2" smd rect
			(at -0.889 0 270)
			(size 1.016 1.27)
			(layers "B.Cu" "B.Mask" "B.Paste")
			(net "GND")
		)
	)
	(footprint ""
		(layer "B.Cu")
		(at 162.7124 -424.60037 -90)
		(property "Reference" "R1512"
			(at 0 0 90)
			(layer "B.SilkS")
			(hide yes)
			(effects
				(font
					(size 1.27 1.27)
				)
				(justify mirror)
			)
		)
		(property "Value" ""
			(at 0 0 90)
			(layer "B.Fab")
			(effects
				(font
					(size 1.27 1.27)
				)
				(justify mirror)
			)
		)
		(duplicate_pad_numbers_are_jumpers no)
		(fp_line
			(start -0.32512 0.175006)
			(end 0.32512 0.175006)
			(stroke
				(width 0.1)
				(type default)
			)
			(layer "B.Fab")
		)
		(fp_line
			(start 0.32512 0.175006)
			(end 0.32512 -0.175006)
			(stroke
				(width 0.1)
				(type default)
			)
			(layer "B.Fab")
		)
		(fp_line
			(start -0.32512 -0.175006)
			(end -0.32512 0.175006)
			(stroke
				(width 0.1)
				(type default)
			)
			(layer "B.Fab")
		)
		(fp_line
			(start 0.32512 -0.175006)
			(end -0.32512 -0.175006)
			(stroke
				(width 0.1)
				(type default)
			)
			(layer "B.Fab")
		)
		(pad "1" smd rect
			(at 0.2667 0 90)
			(size 0.3048 0.381)
			(layers "B.Cu" "B.Mask" "B.Paste")
			(net "P1V8_CPU1_RT_1D")
		)
		(pad "2" smd rect
			(at -0.2667 0 270)
			(size 0.3048 0.381)
			(layers "B.Cu" "B.Mask" "B.Paste")
			(net "JTAG_TDO_RT_CPU1_P3")
		)
	)
	(footprint ""
		(layer "B.Cu")
		(at 403.018752 -398.942052 90)
		(property "Reference" "C803"
			(at 0 0 90)
			(layer "B.SilkS")
			(hide yes)
			(effects
				(font
					(size 1.27 1.27)
				)
				(justify mirror)
			)
		)
		(property "Value" ""
			(at 0 0 90)
			(layer "B.Fab")
			(effects
				(font
					(size 1.27 1.27)
				)
				(justify mirror)
			)
		)
		(duplicate_pad_numbers_are_jumpers no)
		(fp_line
			(start 0.7874 -0.4064)
			(end -0.7874 -0.4064)
			(stroke
				(width 0.1524)
				(type default)
			)
			(layer "B.SilkS")
		)
		(fp_line
			(start -0.7874 -0.4064)
			(end -0.7874 0.4064)
			(stroke
				(width 0.1524)
				(type default)
			)
			(layer "B.SilkS")
		)
		(fp_line
			(start 0.7874 0.4064)
			(end 0.7874 -0.4064)
			(stroke
				(width 0.1524)
				(type default)
			)
			(layer "B.SilkS")
		)
		(fp_line
			(start -0.7874 0.4064)
			(end 0.7874 0.4064)
			(stroke
				(width 0.1524)
				(type default)
			)
			(layer "B.SilkS")
		)
		(fp_line
			(start 0.67945 -0.305054)
			(end 0.12065 -0.305054)
			(stroke
				(width 0.1)
				(type default)
			)
			(layer "B.Fab")
		)
		(fp_line
			(start 0.12065 -0.305054)
			(end 0.12065 -0.2794)
			(stroke
				(width 0.1)
				(type default)
			)
			(layer "B.Fab")
		)
		(fp_line
			(start -0.12065 -0.3048)
			(end -0.67945 -0.3048)
			(stroke
				(width 0.1)
				(type default)
			)
			(layer "B.Fab")
		)
		(fp_line
			(start -0.67945 -0.3048)
			(end -0.67945 0.3048)
			(stroke
				(width 0.1)
				(type default)
			)
			(layer "B.Fab")
		)
		(fp_line
			(start 0.12065 -0.2794)
			(end -0.12065 -0.2794)
			(stroke
				(width 0.1)
				(type default)
			)
			(layer "B.Fab")
		)
		(fp_line
			(start -0.12065 -0.2794)
			(end -0.12065 -0.3048)
			(stroke
				(width 0.1)
				(type default)
			)
			(layer "B.Fab")
		)
		(fp_line
			(start 0.12065 0.2794)
			(end 0.12065 0.3048)
			(stroke
				(width 0.1)
				(type default)
			)
			(layer "B.Fab")
		)
		(fp_line
			(start -0.120396 0.2794)
			(end 0.12065 0.2794)
			(stroke
				(width 0.1)
				(type default)
			)
			(layer "B.Fab")
		)
		(fp_line
			(start 0.67945 0.3048)
			(end 0.67945 -0.305054)
			(stroke
				(width 0.1)
				(type default)
			)
			(layer "B.Fab")
		)
		(fp_line
			(start 0.12065 0.3048)
			(end 0.67945 0.3048)
			(stroke
				(width 0.1)
				(type default)
			)
			(layer "B.Fab")
		)
		(fp_line
			(start -0.120396 0.3048)
			(end -0.120396 0.2794)
			(stroke
				(width 0.1)
				(type default)
			)
			(layer "B.Fab")
		)
		(fp_line
			(start -0.67945 0.3048)
			(end -0.120396 0.3048)
			(stroke
				(width 0.1)
				(type default)
			)
			(layer "B.Fab")
		)
		(pad "1" smd circle
			(at 0.40005 0 270)
			(size 0 0)
			(layers "B.Cu" "B.Mask" "B.Paste")
			(net "P0V9_CPU0_RT2_2A")
		)
		(pad "2" smd circle
			(at -0.40005 0 270)
			(size 0 0)
			(layers "B.Cu" "B.Mask" "B.Paste")
			(net "GND")
		)
	)
)
